#ISCELL
  mstr_misc dns *
  *
#ISCELL
  pure_quanta quanta_title_block_c *
  *
#CELL
  pure_quanta q_res *
  page280_i1
#ISCELL
  standard offpage *
  page280_i10
#CELL
  pure_quanta q_cap *
  page280_i11
#ISCELL
  logical_power universal_gnd *
  page280_i12
#CELL
  pure_quanta q_res *
  page280_i13
#CELL
  pure_quanta raa2213404gnphb0 *
  page280_i14
#CELL
  pure_quanta q_res *
  page280_i15
#CELL
  pure_quanta q_res *
  page280_i16
#ISCELL
  logical_power vcc15 *
  page280_i17
#CELL
  pure_quanta q_res *
  page280_i18
#ISCELL
  logical_power universal_gnd *
  page280_i19
#ISCELL
  logical_power universal_gnd *
  page280_i2
#CELL
  pure_quanta q_res *
  page280_i20
#ISCELL
  logical_power vcc15 *
  page280_i21
#CELL
  pure_quanta q_cap *
  page280_i22
#CELL
  pure_quanta q_inductor *
  page280_i23
#CELL
  pure_quanta q_cap *
  page280_i24
#CELL
  pure_quanta q_res *
  page280_i25
#CELL
  pure_quanta q_cap *
  page280_i26
#CELL
  pure_quanta q_cap *
  page280_i27
#CELL
  pure_quanta q_cap *
  page280_i28
#CELL
  pure_quanta q_cap *
  page280_i29
#ISCELL
  logical_power universal_gnd *
  page280_i3
#CELL
  pure_quanta q_cap *
  page280_i30
#CELL
  pure_quanta q_cap *
  page280_i31
#CELL
  pure_quanta q_capp *
  page280_i32
#CELL
  pure_quanta q_capp *
  page280_i33
#ISCELL
  logical_power universal_gnd *
  page280_i34
#ISCELL
  logical_power vcc15 *
  page280_i35
#ISCELL
  logical_power universal_gnd *
  page280_i36
#CELL
  pure_quanta q_res *
  page280_i37
#ISCELL
  logical_power vcc15 *
  page280_i38
#CELL
  pure_quanta q_res *
  page280_i4
#ISCELL
  logical_power vcc15 *
  page280_i5
#ISCELL
  standard offpage *
  page280_i6
#ISCELL
  standard offpage *
  page280_i7
#ISCELL
  standard offpage *
  page280_i8
#CELL
  pure_quanta q_cap *
  page280_i9
